# T6G (Grand Teton) — schematic netlist excerpt (pin names and nets, part order shuffled) for the footprints in the layout excerpt that follows; sources: Cadence DE-HDL packaged netlist, KiCad conversion of 04192023_DAF0TMB3IC0_F0TG_MB_C_brd_V02_OCP.brd

C2136  Q_CAP  22UF 4V 20% X6S  pkg C0402  page 68 : A = PVDDIO_P0 ; B = GND
R3686  Q_RES  0 5% CHIP  pkg 0402LF  page 257 : A = P5V_ADC ; B = P5V_ADC_TIC

(kicad_pcb
	(version 20260206)
	(generator "pcbnew")
	(generator_version "10.0")
	(general
		(thickness 1.6)
		(legacy_teardrops no)
	)
	(paper "A4")
	(title_block
		(title "04192023_DAF0TMB3IC0_F0TG_MB_C_brd_V02_OCP.brd")
		(comment 1 "Grand Teton / footprints 799-800 of 8354")
	)
	(layers
		(0 "F.Cu" signal "TOP")
		(4 "In1.Cu" signal "GND")
		(6 "In2.Cu" signal "IN1")
		(8 "In3.Cu" signal "GND1")
		(10 "In4.Cu" signal "IN2")
		(12 "In5.Cu" signal "GND2")
		(14 "In6.Cu" signal "IN3")
		(16 "In7.Cu" signal "GND3")
		(18 "In8.Cu" signal "VCC")
		(20 "In9.Cu" signal "VCC1")
		(22 "In10.Cu" signal "GND4")
		(24 "In11.Cu" signal "IN4")
		(26 "In12.Cu" signal "GND5")
		(28 "In13.Cu" signal "IN5")
		(30 "In14.Cu" signal "GND6")
		(32 "In15.Cu" signal "IN6")
		(34 "In16.Cu" signal "GND7")
		(2 "B.Cu" signal "BOTTOM")
		(9 "F.Adhes" user "F.Adhesive")
		(11 "B.Adhes" user "B.Adhesive")
		(13 "F.Paste" user "Package Geometry/Pastemask Top")
		(15 "B.Paste" user "Package Geometry/Pastemask Bottom")
		(5 "F.SilkS" user "Ref Des/Silkscreen Top")
		(7 "B.SilkS" user "Ref Des/Silkscreen Bottom")
		(1 "F.Mask" user "Board Geometry/Soldermask Top")
		(3 "B.Mask" user "Board Geometry/Soldermask Bottom")
		(17 "Dwgs.User" user "User.Drawings")
		(19 "Cmts.User" user "User.Comments")
		(21 "Eco1.User" user "User.Eco1")
		(23 "Eco2.User" user "User.Eco2")
		(25 "Edge.Cuts" user "Board Geometry/Outline")
		(27 "Margin" user)
		(31 "F.CrtYd" user "Package Geometry/Place Bound Top")
		(29 "B.CrtYd" user "Package Geometry/Place Bound Bottom")
		(35 "F.Fab" user "Ref Des/Assembly Top")
		(33 "B.Fab" user "Ref Des/Assembly Bottom")
	)
	(footprint ""
		(layer "F.Cu")
		(at 353.900232 -259.355082)
		(property "Reference" "C2136"
			(at 0 0 0)
			(layer "F.SilkS")
			(hide yes)
			(effects
				(font
					(size 1.27 1.27)
				)
			)
		)
		(property "Value" ""
			(at 0 0 0)
			(layer "F.Fab")
			(effects
				(font
					(size 1.27 1.27)
				)
			)
		)
		(duplicate_pad_numbers_are_jumpers no)
		(fp_line
			(start -0.7874 -0.4064)
			(end 0.7874 -0.4064)
			(stroke
				(width 0.1524)
				(type default)
			)
			(layer "F.SilkS")
		)
		(fp_line
			(start -0.7874 0.4064)
			(end -0.7874 -0.4064)
			(stroke
				(width 0.1524)
				(type default)
			)
			(layer "F.SilkS")
		)
		(fp_line
			(start 0.7874 -0.4064)
			(end 0.7874 0.4064)
			(stroke
				(width 0.1524)
				(type default)
			)
			(layer "F.SilkS")
		)
		(fp_line
			(start 0.7874 0.4064)
			(end -0.7874 0.4064)
			(stroke
				(width 0.1524)
				(type default)
			)
			(layer "F.SilkS")
		)
		(fp_line
			(start -0.67945 -0.305054)
			(end -0.12065 -0.305054)
			(stroke
				(width 0.1)
				(type default)
			)
			(layer "F.Fab")
		)
		(fp_line
			(start -0.67945 0.3048)
			(end -0.67945 -0.305054)
			(stroke
				(width 0.1)
				(type default)
			)
			(layer "F.Fab")
		)
		(fp_line
			(start -0.12065 -0.305054)
			(end -0.12065 -0.2794)
			(stroke
				(width 0.1)
				(type default)
			)
			(layer "F.Fab")
		)
		(fp_line
			(start -0.12065 -0.2794)
			(end 0.12065 -0.2794)
			(stroke
				(width 0.1)
				(type default)
			)
			(layer "F.Fab")
		)
		(fp_line
			(start -0.12065 0.2794)
			(end -0.12065 0.3048)
			(stroke
				(width 0.1)
				(type default)
			)
			(layer "F.Fab")
		)
		(fp_line
			(start -0.12065 0.3048)
			(end -0.67945 0.3048)
			(stroke
				(width 0.1)
				(type default)
			)
			(layer "F.Fab")
		)
		(fp_line
			(start 0.120396 0.2794)
			(end -0.12065 0.2794)
			(stroke
				(width 0.1)
				(type default)
			)
			(layer "F.Fab")
		)
		(fp_line
			(start 0.120396 0.3048)
			(end 0.120396 0.2794)
			(stroke
				(width 0.1)
				(type default)
			)
			(layer "F.Fab")
		)
		(fp_line
			(start 0.12065 -0.3048)
			(end 0.67945 -0.3048)
			(stroke
				(width 0.1)
				(type default)
			)
			(layer "F.Fab")
		)
		(fp_line
			(start 0.12065 -0.2794)
			(end 0.12065 -0.3048)
			(stroke
				(width 0.1)
				(type default)
			)
			(layer "F.Fab")
		)
		(fp_line
			(start 0.67945 -0.3048)
			(end 0.67945 0.3048)
			(stroke
				(width 0.1)
				(type default)
			)
			(layer "F.Fab")
		)
		(fp_line
			(start 0.67945 0.3048)
			(end 0.120396 0.3048)
			(stroke
				(width 0.1)
				(type default)
			)
			(layer "F.Fab")
		)
		(pad "1" smd circle
			(at -0.40005 0)
			(size 0 0)
			(layers "F.Cu" "F.Mask" "F.Paste")
			(net "PVDDIO_P0")
		)
		(pad "2" smd circle
			(at 0.40005 0)
			(size 0 0)
			(layers "F.Cu" "F.Mask" "F.Paste")
			(net "GND")
		)
	)
	(footprint ""
		(layer "F.Cu")
		(at 322.837048 -43.573954 180)
		(property "Reference" "R3686"
			(at 0 0 180)
			(layer "F.SilkS")
			(hide yes)
			(effects
				(font
					(size 1.27 1.27)
				)
			)
		)
		(property "Value" ""
			(at 0 0 180)
			(layer "F.Fab")
			(effects
				(font
					(size 1.27 1.27)
				)
			)
		)
		(duplicate_pad_numbers_are_jumpers no)
		(fp_line
			(start 0.7874 0.4064)
			(end -0.7874 0.4064)
			(stroke
				(width 0.1524)
				(type default)
			)
			(layer "F.SilkS")
		)
		(fp_line
			(start 0.7874 -0.4064)
			(end 0.7874 0.4064)
			(stroke
				(width 0.1524)
				(type default)
			)
			(layer "F.SilkS")
		)
		(fp_line
			(start -0.7874 0.4064)
			(end -0.7874 -0.4064)
			(stroke
				(width 0.1524)
				(type default)
			)
			(layer "F.SilkS")
		)
		(fp_line
			(start -0.7874 -0.4064)
			(end 0.7874 -0.4064)
			(stroke
				(width 0.1524)
				(type default)
			)
			(layer "F.SilkS")
		)
		(fp_line
			(start 0.67945 0.3048)
			(end 0.120396 0.3048)
			(stroke
				(width 0.1)
				(type default)
			)
			(layer "F.Fab")
		)
		(fp_line
			(start 0.67945 -0.3048)
			(end 0.67945 0.3048)
			(stroke
				(width 0.1)
				(type default)
			)
			(layer "F.Fab")
		)
		(fp_line
			(start 0.12065 -0.2794)
			(end 0.12065 -0.3048)
			(stroke
				(width 0.1)
				(type default)
			)
			(layer "F.Fab")
		)
		(fp_line
			(start 0.12065 -0.3048)
			(end 0.67945 -0.3048)
			(stroke
				(width 0.1)
				(type default)
			)
			(layer "F.Fab")
		)
		(fp_line
			(start 0.120396 0.3048)
			(end 0.120396 0.2794)
			(stroke
				(width 0.1)
				(type default)
			)
			(layer "F.Fab")
		)
		(fp_line
			(start 0.120396 0.2794)
			(end -0.12065 0.2794)
			(stroke
				(width 0.1)
				(type default)
			)
			(layer "F.Fab")
		)
		(fp_line
			(start -0.12065 0.3048)
			(end -0.67945 0.3048)
			(stroke
				(width 0.1)
				(type default)
			)
			(layer "F.Fab")
		)
		(fp_line
			(start -0.12065 0.2794)
			(end -0.12065 0.3048)
			(stroke
				(width 0.1)
				(type default)
			)
			(layer "F.Fab")
		)
		(fp_line
			(start -0.12065 -0.2794)
			(end 0.12065 -0.2794)
			(stroke
				(width 0.1)
				(type default)
			)
			(layer "F.Fab")
		)
		(fp_line
			(start -0.12065 -0.305054)
			(end -0.12065 -0.2794)
			(stroke
				(width 0.1)
				(type default)
			)
			(layer "F.Fab")
		)
		(fp_line
			(start -0.67945 0.3048)
			(end -0.67945 -0.305054)
			(stroke
				(width 0.1)
				(type default)
			)
			(layer "F.Fab")
		)
		(fp_line
			(start -0.67945 -0.305054)
			(end -0.12065 -0.305054)
			(stroke
				(width 0.1)
				(type default)
			)
			(layer "F.Fab")
		)
		(pad "1" smd rect
			(at -0.40005 0)
			(size 0.4572 0.508)
			(layers "F.Cu" "F.Mask" "F.Paste")
			(net "P5V_ADC")
		)
		(pad "2" smd rect
			(at 0.40005 0)
			(size 0.4572 0.508)
			(layers "F.Cu" "F.Mask" "F.Paste")
			(net "P5V_ADC_TIC")
		)
	)
)
